# T6G (Grand Teton) — schematic netlist excerpt (pin names and nets, part order shuffled) for the footprints in the layout excerpt that follows; sources: Cadence DE-HDL packaged netlist, KiCad conversion of 04192023_DAF0TMB3IC0_F0TG_MB_C_brd_V02_OCP.brd

Q19  BSS138DW7F  BSS138DW-7-F IC  pkg SOT363A  page 259
  S1  = GND
  G1  = PWRGD_P12V_MEM_CPU1_EN
  D2  = PWRGD_P12V_MEM_CPU1
  S2  = GND
  G2  = PWRGD_P12V_MEM_CPU1_EN_N
  D1  = PWRGD_P12V_MEM_CPU1_EN_N

PC1853  Q_CAP  0.1UF 25V 10% X7R  pkg 0402  page 189 : A = P5V_AUX_REF ; B = GND

(kicad_pcb
	(version 20260206)
	(generator "pcbnew")
	(generator_version "10.0")
	(general
		(thickness 1.6)
		(legacy_teardrops no)
	)
	(paper "A4")
	(title_block
		(title "04192023_DAF0TMB3IC0_F0TG_MB_C_brd_V02_OCP.brd")
		(comment 1 "Grand Teton / footprints 189-190 of 8354")
	)
	(layers
		(0 "F.Cu" signal "TOP")
		(4 "In1.Cu" signal "GND")
		(6 "In2.Cu" signal "IN1")
		(8 "In3.Cu" signal "GND1")
		(10 "In4.Cu" signal "IN2")
		(12 "In5.Cu" signal "GND2")
		(14 "In6.Cu" signal "IN3")
		(16 "In7.Cu" signal "GND3")
		(18 "In8.Cu" signal "VCC")
		(20 "In9.Cu" signal "VCC1")
		(22 "In10.Cu" signal "GND4")
		(24 "In11.Cu" signal "IN4")
		(26 "In12.Cu" signal "GND5")
		(28 "In13.Cu" signal "IN5")
		(30 "In14.Cu" signal "GND6")
		(32 "In15.Cu" signal "IN6")
		(34 "In16.Cu" signal "GND7")
		(2 "B.Cu" signal "BOTTOM")
		(9 "F.Adhes" user "F.Adhesive")
		(11 "B.Adhes" user "B.Adhesive")
		(13 "F.Paste" user "Package Geometry/Pastemask Top")
		(15 "B.Paste" user "Package Geometry/Pastemask Bottom")
		(5 "F.SilkS" user "Ref Des/Silkscreen Top")
		(7 "B.SilkS" user "Ref Des/Silkscreen Bottom")
		(1 "F.Mask" user "Board Geometry/Soldermask Top")
		(3 "B.Mask" user "Board Geometry/Soldermask Bottom")
		(17 "Dwgs.User" user "User.Drawings")
		(19 "Cmts.User" user "User.Comments")
		(21 "Eco1.User" user "User.Eco1")
		(23 "Eco2.User" user "User.Eco2")
		(25 "Edge.Cuts" user "Board Geometry/Outline")
		(27 "Margin" user)
		(31 "F.CrtYd" user "Package Geometry/Place Bound Top")
		(29 "B.CrtYd" user "Package Geometry/Place Bound Bottom")
		(35 "F.Fab" user "Ref Des/Assembly Top")
		(33 "B.Fab" user "Ref Des/Assembly Bottom")
	)
	(footprint ""
		(layer "F.Cu")
		(at 409.434792 -140.884656 180)
		(property "Reference" "PC1853"
			(at 0 0 180)
			(layer "F.SilkS")
			(hide yes)
			(effects
				(font
					(size 1.27 1.27)
				)
			)
		)
		(property "Value" ""
			(at 0 0 180)
			(layer "F.Fab")
			(effects
				(font
					(size 1.27 1.27)
				)
			)
		)
		(duplicate_pad_numbers_are_jumpers no)
		(fp_line
			(start 0.7874 0.4064)
			(end -0.7874 0.4064)
			(stroke
				(width 0.1524)
				(type default)
			)
			(layer "F.SilkS")
		)
		(fp_line
			(start 0.7874 -0.4064)
			(end 0.7874 0.4064)
			(stroke
				(width 0.1524)
				(type default)
			)
			(layer "F.SilkS")
		)
		(fp_line
			(start -0.7874 0.4064)
			(end -0.7874 -0.4064)
			(stroke
				(width 0.1524)
				(type default)
			)
			(layer "F.SilkS")
		)
		(fp_line
			(start -0.7874 -0.4064)
			(end 0.7874 -0.4064)
			(stroke
				(width 0.1524)
				(type default)
			)
			(layer "F.SilkS")
		)
		(fp_line
			(start 0.67945 0.3048)
			(end 0.120396 0.3048)
			(stroke
				(width 0.1)
				(type default)
			)
			(layer "F.Fab")
		)
		(fp_line
			(start 0.67945 -0.3048)
			(end 0.67945 0.3048)
			(stroke
				(width 0.1)
				(type default)
			)
			(layer "F.Fab")
		)
		(fp_line
			(start 0.12065 -0.2794)
			(end 0.12065 -0.3048)
			(stroke
				(width 0.1)
				(type default)
			)
			(layer "F.Fab")
		)
		(fp_line
			(start 0.12065 -0.3048)
			(end 0.67945 -0.3048)
			(stroke
				(width 0.1)
				(type default)
			)
			(layer "F.Fab")
		)
		(fp_line
			(start 0.120396 0.3048)
			(end 0.120396 0.2794)
			(stroke
				(width 0.1)
				(type default)
			)
			(layer "F.Fab")
		)
		(fp_line
			(start 0.120396 0.2794)
			(end -0.12065 0.2794)
			(stroke
				(width 0.1)
				(type default)
			)
			(layer "F.Fab")
		)
		(fp_line
			(start -0.12065 0.3048)
			(end -0.67945 0.3048)
			(stroke
				(width 0.1)
				(type default)
			)
			(layer "F.Fab")
		)
		(fp_line
			(start -0.12065 0.2794)
			(end -0.12065 0.3048)
			(stroke
				(width 0.1)
				(type default)
			)
			(layer "F.Fab")
		)
		(fp_line
			(start -0.12065 -0.2794)
			(end 0.12065 -0.2794)
			(stroke
				(width 0.1)
				(type default)
			)
			(layer "F.Fab")
		)
		(fp_line
			(start -0.12065 -0.305054)
			(end -0.12065 -0.2794)
			(stroke
				(width 0.1)
				(type default)
			)
			(layer "F.Fab")
		)
		(fp_line
			(start -0.67945 0.3048)
			(end -0.67945 -0.305054)
			(stroke
				(width 0.1)
				(type default)
			)
			(layer "F.Fab")
		)
		(fp_line
			(start -0.67945 -0.305054)
			(end -0.12065 -0.305054)
			(stroke
				(width 0.1)
				(type default)
			)
			(layer "F.Fab")
		)
		(pad "1" smd circle
			(at -0.40005 0 180)
			(size 0 0)
			(layers "F.Cu" "F.Mask" "F.Paste")
			(net "P5V_AUX_REF")
		)
		(pad "2" smd circle
			(at 0.40005 0 180)
			(size 0 0)
			(layers "F.Cu" "F.Mask" "F.Paste")
			(net "GND")
		)
	)
	(footprint ""
		(layer "F.Cu")
		(at 105.659936 -123.623832 -90)
		(property "Reference" "Q19"
			(at -0.177546 1.643126 90)
			(unlocked yes)
			(layer "F.SilkS")
			(effects
				(font
					(size 0.7874 0.5842)
					(thickness 0.1524)
				)
			)
		)
		(property "Value" ""
			(at 0 0 270)
			(layer "F.Fab")
			(effects
				(font
					(size 1.27 1.27)
				)
			)
		)
		(duplicate_pad_numbers_are_jumpers no)
		(fp_line
			(start -1.7018 1.100074)
			(end -1.7018 -1.100074)
			(stroke
				(width 0.1524)
				(type default)
			)
			(layer "F.SilkS")
		)
		(fp_line
			(start 1.7018 1.100074)
			(end -1.7018 1.100074)
			(stroke
				(width 0.1524)
				(type default)
			)
			(layer "F.SilkS")
		)
		(fp_line
			(start -1.7018 -1.100074)
			(end 1.7018 -1.100074)
			(stroke
				(width 0.1524)
				(type default)
			)
			(layer "F.SilkS")
		)
		(fp_line
			(start 1.7018 -1.100074)
			(end 1.7018 1.100074)
			(stroke
				(width 0.1524)
				(type default)
			)
			(layer "F.SilkS")
		)
		(fp_poly
			(pts
				(xy -2.277618 -0.710946) (xy -2.831338 -0.414274) (xy -2.831338 -1.039114)
			)
			(stroke
				(width 0)
				(type default)
			)
			(fill yes)
			(layer "F.SilkS")
		)
		(fp_line
			(start -0.670052 1.100074)
			(end -0.670052 0.8001)
			(stroke
				(width 0.1)
				(type default)
			)
			(layer "F.Fab")
		)
		(fp_line
			(start 0.670052 1.100074)
			(end -0.670052 1.100074)
			(stroke
				(width 0.1)
				(type default)
			)
			(layer "F.Fab")
		)
		(fp_line
			(start -1.100074 0.8001)
			(end -1.100074 -0.8001)
			(stroke
				(width 0.1)
				(type default)
			)
			(layer "F.Fab")
		)
		(fp_line
			(start -0.670052 0.8001)
			(end -1.100074 0.8001)
			(stroke
				(width 0.1)
				(type default)
			)
			(layer "F.Fab")
		)
		(fp_line
			(start -0.670052 0.8001)
			(end -0.670052 -0.8001)
			(stroke
				(width 0.1)
				(type default)
			)
			(layer "F.Fab")
		)
		(fp_line
			(start 0.670052 0.8001)
			(end 0.670052 1.100074)
			(stroke
				(width 0.1)
				(type default)
			)
			(layer "F.Fab")
		)
		(fp_line
			(start 1.100074 0.8001)
			(end 0.670052 0.8001)
			(stroke
				(width 0.1)
				(type default)
			)
			(layer "F.Fab")
		)
		(fp_line
			(start -1.100074 -0.8001)
			(end -0.670052 -0.8001)
			(stroke
				(width 0.1)
				(type default)
			)
			(layer "F.Fab")
		)
		(fp_line
			(start -0.670052 -0.8001)
			(end -0.670052 -1.100074)
			(stroke
				(width 0.1)
				(type default)
			)
			(layer "F.Fab")
		)
		(fp_line
			(start 0.670052 -0.8001)
			(end 0.670052 0.8001)
			(stroke
				(width 0.1)
				(type default)
			)
			(layer "F.Fab")
		)
		(fp_line
			(start 0.670052 -0.8001)
			(end 1.100074 -0.8001)
			(stroke
				(width 0.1)
				(type default)
			)
			(layer "F.Fab")
		)
		(fp_line
			(start 1.100074 -0.8001)
			(end 1.100074 0.8001)
			(stroke
				(width 0.1)
				(type default)
			)
			(layer "F.Fab")
		)
		(fp_line
			(start -0.670052 -1.100074)
			(end 0.670052 -1.100074)
			(stroke
				(width 0.1)
				(type default)
			)
			(layer "F.Fab")
		)
		(fp_line
			(start 0.670052 -1.100074)
			(end 0.670052 -0.8001)
			(stroke
				(width 0.1)
				(type default)
			)
			(layer "F.Fab")
		)
		(fp_poly
			(pts
				(xy -2.33172 -0.338328) (xy -2.33172 -0.963168) (xy -1.778 -0.635)
			)
			(stroke
				(width 0)
				(type default)
			)
			(fill yes)
			(layer "F.Fab")
		)
		(pad "1" smd rect
			(at -0.937514 -0.649986)
			(size 0.3048 1.2446)
			(layers "F.Cu" "F.Mask" "F.Paste")
			(net "GND")
		)
		(pad "2" smd rect
			(at -0.937514 0)
			(size 0.3048 1.2446)
			(layers "F.Cu" "F.Mask" "F.Paste")
			(net "PWRGD_P12V_MEM_CPU1_EN")
		)
		(pad "3" smd rect
			(at -0.937514 0.649986)
			(size 0.3048 1.2446)
			(layers "F.Cu" "F.Mask" "F.Paste")
			(net "PWRGD_P12V_MEM_CPU1")
		)
		(pad "4" smd rect
			(at 0.937514 0.649986)
			(size 0.3048 1.2446)
			(layers "F.Cu" "F.Mask" "F.Paste")
			(net "GND")
		)
		(pad "5" smd rect
			(at 0.937514 0)
			(size 0.3048 1.2446)
			(layers "F.Cu" "F.Mask" "F.Paste")
			(net "PWRGD_P12V_MEM_CPU1_EN_N")
		)
		(pad "6" smd rect
			(at 0.937514 -0.649986)
			(size 0.3048 1.2446)
			(layers "F.Cu" "F.Mask" "F.Paste")
			(net "PWRGD_P12V_MEM_CPU1_EN_N")
		)
	)
)
